(kicad_pcb
	(version 20260206)
	(generator "pcbnew")
	(generator_version "10.0")
	(general
		(thickness 1.6)
		(legacy_teardrops no)
	)
	(paper "A4")
	(title_block
		(title "dpb — 14545-sa.0730WZS0815.brd")
		(comment 1 "Honey Badger (Wiwynn) / footprints 102-108 of 1066")
	)
	(layers
		(0 "F.Cu" signal "TOP")
		(4 "In1.Cu" signal "L2GND")
		(6 "In2.Cu" signal "L3")
		(8 "In3.Cu" signal "L4VCC")
		(10 "In4.Cu" signal "L5VCC")
		(12 "In5.Cu" signal "L6")
		(14 "In6.Cu" signal "L7GND")
		(2 "B.Cu" signal "BOTTOM")
		(9 "F.Adhes" user "F.Adhesive")
		(11 "B.Adhes" user "B.Adhesive")
		(13 "F.Paste" user "Package Geometry/Pastemask Top")
		(15 "B.Paste" user "Package Geometry/Pastemask Bottom")
		(5 "F.SilkS" user "Ref Des/Silkscreen Top")
		(7 "B.SilkS" user "Ref Des/Silkscreen Bottom")
		(1 "F.Mask" user "Board Geometry/Soldermask Top")
		(3 "B.Mask" user "Board Geometry/Soldermask Bottom")
		(17 "Dwgs.User" user "User.Drawings")
		(19 "Cmts.User" user "User.Comments")
		(21 "Eco1.User" user "User.Eco1")
		(23 "Eco2.User" user "User.Eco2")
		(25 "Edge.Cuts" user "Board Geometry/Outline")
		(27 "Margin" user)
		(31 "F.CrtYd" user "Package Geometry/Place Bound Top")
		(29 "B.CrtYd" user "Package Geometry/Place Bound Bottom")
		(35 "F.Fab" user "Ref Des/Assembly Top")
		(33 "B.Fab" user "Ref Des/Assembly Bottom")
	)
	(footprint ""
		(layer "F.Cu")
		(at 80.01 -199.517 -90)
		(property "Reference" "D23"
			(at 0 0 270)
			(layer "F.SilkS")
			(hide yes)
			(effects
				(font
					(size 1.27 1.27)
				)
			)
		)
		(property "Value" "RB551V30-1-GP"
			(at 0 -6.7818 270)
			(unlocked yes)
			(layer "F.Fab")
			(hide yes)
			(effects
				(font
					(size 1.016 1.016)
					(thickness 0.1524)
				)
			)
		)
		(property "Device Type" "SOD323AKH44"
			(at 0 -8.6868 270)
			(unlocked yes)
			(layer "F.Fab")
			(hide yes)
			(effects
				(font
					(size 1.016 1.016)
					(thickness 0.1524)
				)
			)
		)
		(duplicate_pad_numbers_are_jumpers no)
		(fp_line
			(start -0.889 2.159)
			(end -0.889 -1.9304)
			(stroke
				(width 0.1524)
				(type default)
			)
			(layer "F.SilkS")
		)
		(fp_line
			(start 0.889 2.159)
			(end -0.889 2.159)
			(stroke
				(width 0.1524)
				(type default)
			)
			(layer "F.SilkS")
		)
		(fp_line
			(start 0.762 2.0574)
			(end -0.762 2.0574)
			(stroke
				(width 0.508)
				(type default)
			)
			(layer "F.SilkS")
		)
		(fp_line
			(start -0.889 -1.9304)
			(end 0.889 -1.9304)
			(stroke
				(width 0.1524)
				(type default)
			)
			(layer "F.SilkS")
		)
		(fp_line
			(start 0.889 -1.9304)
			(end 0.889 2.159)
			(stroke
				(width 0.1524)
				(type default)
			)
			(layer "F.SilkS")
		)
		(fp_rect
			(start -1.016 2.3114)
			(end 1.016 -2.0066)
			(stroke
				(width 0)
				(type default)
			)
			(fill no)
			(layer "F.CrtYd")
		)
		(fp_poly
			(pts
				(xy -1.016 -2.0066) (xy 1.016 -2.0066) (xy 1.016 2.3114) (xy -1.016 2.3114)
			)
			(stroke
				(width 0)
				(type default)
			)
			(fill no)
			(layer "F.Fab")
		)
		(pad "A" smd rect
			(at 0 -1.143 270)
			(size 0.5588 1.016)
			(layers "F.Cu" "F.Mask" "F.Paste")
			(net "SW_HDD8_R")
		)
		(pad "K" smd rect
			(at 0 1.143 270)
			(size 0.5588 1.016)
			(layers "F.Cu" "F.Mask" "F.Paste")
			(net "SW_HDD8_N")
		)
	)
	(footprint ""
		(layer "F.Cu")
		(at 45.770546 -133.3119 90)
		(property "Reference" "C341"
			(at 0 0 90)
			(layer "F.SilkS")
			(hide yes)
			(effects
				(font
					(size 1.27 1.27)
				)
			)
		)
		(property "Value" "SCD1U10V2KX-5GP"
			(at 1.1811 -2.7051 90)
			(unlocked yes)
			(layer "F.Fab")
			(hide yes)
			(effects
				(font
					(size 1.016 1.016)
					(thickness 0.1524)
				)
			)
		)
		(property "Device Type" "C402H22"
			(at 1.1811 -4.2291 90)
			(unlocked yes)
			(layer "F.Fab")
			(hide yes)
			(effects
				(font
					(size 1.016 1.016)
					(thickness 0.1524)
				)
			)
		)
		(duplicate_pad_numbers_are_jumpers no)
		(fp_rect
			(start -0.4318 0.9525)
			(end 0.4318 -0.9525)
			(stroke
				(width 0)
				(type default)
			)
			(fill no)
			(layer "F.CrtYd")
		)
		(fp_rect
			(start -0.4318 0.9525)
			(end 0.4318 -0.9525)
			(stroke
				(width 0)
				(type default)
			)
			(fill no)
			(layer "F.Fab")
		)
		(pad "1" smd custom
			(at 0 -0.4445 90)
			(size 0.1524 0.1524)
			(layers "F.Cu" "F.Mask" "F.Paste")
			(net "P3V3")
			(options
				(clearance outline)
				(anchor circle)
			)
			(primitives
				(gr_poly
					(pts
						(arc
							(start 0.3048 -0.2032)
							(mid 0.275042 -0.275042)
							(end 0.2032 -0.3048)
						)
						(arc
							(start -0.2032 -0.3048)
							(mid -0.275042 -0.275042)
							(end -0.3048 -0.2032)
						)
						(arc
							(start -0.3048 0.2032)
							(mid -0.275042 0.275042)
							(end -0.2032 0.3048)
						)
						(arc
							(start 0.2032 0.3048)
							(mid 0.275042 0.275042)
							(end 0.3048 0.2032)
						)
					)
					(width 0)
					(fill yes)
				)
			)
		)
		(pad "2" smd custom
			(at 0 0.4445 90)
			(size 0.1524 0.1524)
			(layers "F.Cu" "F.Mask" "F.Paste")
			(net "GND")
			(options
				(clearance outline)
				(anchor circle)
			)
			(primitives
				(gr_poly
					(pts
						(arc
							(start 0.3048 -0.2032)
							(mid 0.275042 -0.275042)
							(end 0.2032 -0.3048)
						)
						(arc
							(start -0.2032 -0.3048)
							(mid -0.275042 -0.275042)
							(end -0.3048 -0.2032)
						)
						(arc
							(start -0.3048 0.2032)
							(mid -0.275042 0.275042)
							(end -0.2032 0.3048)
						)
						(arc
							(start 0.2032 0.3048)
							(mid 0.275042 0.275042)
							(end 0.3048 0.2032)
						)
					)
					(width 0)
					(fill yes)
				)
			)
		)
	)
	(footprint ""
		(layer "F.Cu")
		(at 47.116746 -30.2387 180)
		(property "Reference" "PR21"
			(at 0 0 180)
			(layer "F.SilkS")
			(hide yes)
			(effects
				(font
					(size 1.27 1.27)
				)
			)
		)
		(property "Value" "10R2F-L-GP"
			(at 0.064008 -3.993896 180)
			(unlocked yes)
			(layer "F.Fab")
			(hide yes)
			(effects
				(font
					(size 1.016 1.016)
					(thickness 0.1524)
				)
			)
		)
		(property "Device Type" "R402H14"
			(at 0.064008 -5.517896 180)
			(unlocked yes)
			(layer "F.Fab")
			(hide yes)
			(effects
				(font
					(size 1.016 1.016)
					(thickness 0.1524)
				)
			)
		)
		(duplicate_pad_numbers_are_jumpers no)
		(fp_line
			(start 0.508 -0.9398)
			(end -0.508 -0.9398)
			(stroke
				(width 0.1524)
				(type default)
			)
			(layer "F.SilkS")
		)
		(fp_line
			(start -0.508 -0.9398)
			(end -0.508 0.9398)
			(stroke
				(width 0.1524)
				(type default)
			)
			(layer "F.SilkS")
		)
		(fp_rect
			(start -0.508 0.9398)
			(end 0.508 -0.9398)
			(stroke
				(width 0)
				(type default)
			)
			(fill no)
			(layer "F.CrtYd")
		)
		(fp_rect
			(start -0.508 0.9398)
			(end 0.508 -0.9398)
			(stroke
				(width 0)
				(type default)
			)
			(fill no)
			(layer "F.Fab")
		)
		(pad "1" smd custom
			(at 0 -0.4445 180)
			(size 0.1397 0.1397)
			(layers "F.Cu" "F.Mask" "F.Paste")
			(net "P5VB")
			(options
				(clearance outline)
				(anchor circle)
			)
			(primitives
				(gr_poly
					(pts
						(arc
							(start -0.1778 -0.2794)
							(mid -0.249642 -0.249642)
							(end -0.2794 -0.1778)
						)
						(arc
							(start -0.2794 0.1778)
							(mid -0.249642 0.249642)
							(end -0.1778 0.2794)
						)
						(arc
							(start 0.1778 0.2794)
							(mid 0.249642 0.249642)
							(end 0.2794 0.1778)
						)
						(arc
							(start 0.2794 -0.1778)
							(mid 0.249642 -0.249642)
							(end 0.1778 -0.2794)
						)
					)
					(width 0)
					(fill yes)
				)
			)
		)
		(pad "2" smd custom
			(at 0 0.4445 180)
			(size 0.1397 0.1397)
			(layers "F.Cu" "F.Mask" "F.Paste")
			(net "P5VB_VFB_NET")
			(options
				(clearance outline)
				(anchor circle)
			)
			(primitives
				(gr_poly
					(pts
						(arc
							(start -0.1778 -0.2794)
							(mid -0.249642 -0.249642)
							(end -0.2794 -0.1778)
						)
						(arc
							(start -0.2794 0.1778)
							(mid -0.249642 0.249642)
							(end -0.1778 0.2794)
						)
						(arc
							(start 0.1778 0.2794)
							(mid 0.249642 0.249642)
							(end 0.2794 0.1778)
						)
						(arc
							(start 0.2794 -0.1778)
							(mid 0.249642 -0.249642)
							(end 0.1778 -0.2794)
						)
					)
					(width 0)
					(fill yes)
				)
			)
		)
	)
	(footprint ""
		(layer "F.Cu")
		(at 210.692746 -52.4637)
		(property "Reference" "R335"
			(at 0 0 0)
			(layer "F.SilkS")
			(hide yes)
			(effects
				(font
					(size 1.27 1.27)
				)
			)
		)
		(property "Value" "0R2J-2-GP"
			(at 0.064008 -3.993896 0)
			(unlocked yes)
			(layer "F.Fab")
			(hide yes)
			(effects
				(font
					(size 1.016 1.016)
					(thickness 0.1524)
				)
			)
		)
		(property "Device Type" "R402H16"
			(at 0.064008 -5.517896 0)
			(unlocked yes)
			(layer "F.Fab")
			(hide yes)
			(effects
				(font
					(size 1.016 1.016)
					(thickness 0.1524)
				)
			)
		)
		(duplicate_pad_numbers_are_jumpers no)
		(fp_line
			(start -0.508 -0.9398)
			(end -0.508 0.9398)
			(stroke
				(width 0.1524)
				(type default)
			)
			(layer "F.SilkS")
		)
		(fp_line
			(start 0.508 -0.9398)
			(end -0.508 -0.9398)
			(stroke
				(width 0.1524)
				(type default)
			)
			(layer "F.SilkS")
		)
		(fp_rect
			(start -0.508 0.9398)
			(end 0.508 -0.9398)
			(stroke
				(width 0)
				(type default)
			)
			(fill no)
			(layer "F.CrtYd")
		)
		(fp_rect
			(start -0.508 0.9398)
			(end 0.508 -0.9398)
			(stroke
				(width 0)
				(type default)
			)
			(fill no)
			(layer "F.Fab")
		)
		(pad "1" smd custom
			(at 0 -0.4445)
			(size 0.1397 0.1397)
			(layers "F.Cu" "F.Mask" "F.Paste")
			(net "I2C_B_SCL")
			(options
				(clearance outline)
				(anchor circle)
			)
			(primitives
				(gr_poly
					(pts
						(arc
							(start -0.1778 -0.2794)
							(mid -0.249642 -0.249642)
							(end -0.2794 -0.1778)
						)
						(arc
							(start -0.2794 0.1778)
							(mid -0.249642 0.249642)
							(end -0.1778 0.2794)
						)
						(arc
							(start 0.1778 0.2794)
							(mid 0.249642 0.249642)
							(end 0.2794 0.1778)
						)
						(arc
							(start 0.2794 -0.1778)
							(mid 0.249642 -0.249642)
							(end 0.1778 -0.2794)
						)
					)
					(width 0)
					(fill yes)
				)
			)
		)
		(pad "2" smd custom
			(at 0 0.4445)
			(size 0.1397 0.1397)
			(layers "F.Cu" "F.Mask" "F.Paste")
			(net "TMP4_SCL")
			(options
				(clearance outline)
				(anchor circle)
			)
			(primitives
				(gr_poly
					(pts
						(arc
							(start -0.1778 -0.2794)
							(mid -0.249642 -0.249642)
							(end -0.2794 -0.1778)
						)
						(arc
							(start -0.2794 0.1778)
							(mid -0.249642 0.249642)
							(end -0.1778 0.2794)
						)
						(arc
							(start 0.1778 0.2794)
							(mid 0.249642 0.249642)
							(end 0.2794 0.1778)
						)
						(arc
							(start 0.2794 -0.1778)
							(mid 0.249642 -0.249642)
							(end 0.1778 -0.2794)
						)
					)
					(width 0)
					(fill yes)
				)
			)
		)
	)
	(footprint ""
		(layer "F.Cu")
		(at 79.191358 -498.396514 90)
		(property "Reference" "R181"
			(at 0 0 90)
			(layer "F.SilkS")
			(hide yes)
			(effects
				(font
					(size 1.27 1.27)
				)
			)
		)
		(property "Value" "200KR2F-L-GP"
			(at 0.064008 -3.993896 90)
			(unlocked yes)
			(layer "F.Fab")
			(hide yes)
			(effects
				(font
					(size 1.016 1.016)
					(thickness 0.1524)
				)
			)
		)
		(property "Device Type" "R402H16"
			(at 0.064008 -5.517896 90)
			(unlocked yes)
			(layer "F.Fab")
			(hide yes)
			(effects
				(font
					(size 1.016 1.016)
					(thickness 0.1524)
				)
			)
		)
		(duplicate_pad_numbers_are_jumpers no)
		(fp_line
			(start 0.508 -0.9398)
			(end -0.508 -0.9398)
			(stroke
				(width 0.1524)
				(type default)
			)
			(layer "F.SilkS")
		)
		(fp_line
			(start -0.508 -0.9398)
			(end -0.508 0.9398)
			(stroke
				(width 0.1524)
				(type default)
			)
			(layer "F.SilkS")
		)
		(fp_rect
			(start -0.508 0.9398)
			(end 0.508 -0.9398)
			(stroke
				(width 0)
				(type default)
			)
			(fill no)
			(layer "F.CrtYd")
		)
		(fp_rect
			(start -0.508 0.9398)
			(end 0.508 -0.9398)
			(stroke
				(width 0)
				(type default)
			)
			(fill no)
			(layer "F.Fab")
		)
		(pad "1" smd custom
			(at 0 -0.4445 90)
			(size 0.1397 0.1397)
			(layers "F.Cu" "F.Mask" "F.Paste")
			(net "P12V")
			(options
				(clearance outline)
				(anchor circle)
			)
			(primitives
				(gr_poly
					(pts
						(arc
							(start -0.1778 -0.2794)
							(mid -0.249642 -0.249642)
							(end -0.2794 -0.1778)
						)
						(arc
							(start -0.2794 0.1778)
							(mid -0.249642 0.249642)
							(end -0.1778 0.2794)
						)
						(arc
							(start 0.1778 0.2794)
							(mid 0.249642 0.249642)
							(end 0.2794 0.1778)
						)
						(arc
							(start 0.2794 -0.1778)
							(mid 0.249642 -0.249642)
							(end 0.1778 -0.2794)
						)
					)
					(width 0)
					(fill yes)
				)
			)
		)
		(pad "2" smd custom
			(at 0 0.4445 90)
			(size 0.1397 0.1397)
			(layers "F.Cu" "F.Mask" "F.Paste")
			(net "SW_HDD5_P")
			(options
				(clearance outline)
				(anchor circle)
			)
			(primitives
				(gr_poly
					(pts
						(arc
							(start -0.1778 -0.2794)
							(mid -0.249642 -0.249642)
							(end -0.2794 -0.1778)
						)
						(arc
							(start -0.2794 0.1778)
							(mid -0.249642 0.249642)
							(end -0.1778 0.2794)
						)
						(arc
							(start 0.1778 0.2794)
							(mid 0.249642 0.249642)
							(end 0.2794 0.1778)
						)
						(arc
							(start 0.2794 -0.1778)
							(mid 0.249642 -0.249642)
							(end 0.1778 -0.2794)
						)
					)
					(width 0)
					(fill yes)
				)
			)
		)
	)
	(footprint ""
		(layer "F.Cu")
		(at 36.449 -140.716)
		(property "Reference" "Q72"
			(at 0 0 0)
			(layer "F.SilkS")
			(hide yes)
			(effects
				(font
					(size 1.27 1.27)
				)
			)
		)
		(property "Value" "2N7002DW-7F-GP"
			(at -2.3622 -8.2042 0)
			(unlocked yes)
			(layer "F.Fab")
			(hide yes)
			(effects
				(font
					(size 1.016 1.016)
					(thickness 0.1524)
				)
			)
		)
		(property "Device Type" "SOT-363H44"
			(at -2.3622 -10.1092 0)
			(unlocked yes)
			(layer "F.Fab")
			(hide yes)
			(effects
				(font
					(size 1.016 1.016)
					(thickness 0.1524)
				)
			)
		)
		(duplicate_pad_numbers_are_jumpers no)
		(fp_line
			(start -1.4478 -1.7018)
			(end -1.4478 1.7018)
			(stroke
				(width 0.1524)
				(type default)
			)
			(layer "F.SilkS")
		)
		(fp_line
			(start -1.4478 1.7018)
			(end 1.4478 1.7018)
			(stroke
				(width 0.1524)
				(type default)
			)
			(layer "F.SilkS")
		)
		(fp_line
			(start -1.27 1.524)
			(end -1.27 0.6604)
			(stroke
				(width 0.4826)
				(type default)
			)
			(layer "F.SilkS")
		)
		(fp_line
			(start 1.4478 -1.7018)
			(end -1.4478 -1.7018)
			(stroke
				(width 0.1524)
				(type default)
			)
			(layer "F.SilkS")
		)
		(fp_line
			(start 1.4478 1.7018)
			(end 1.4478 -1.7018)
			(stroke
				(width 0.1524)
				(type default)
			)
			(layer "F.SilkS")
		)
		(fp_poly
			(pts
				(xy -1.524 -1.778) (xy 1.524 -1.778) (xy 1.524 1.778) (xy -1.524 1.778)
			)
			(stroke
				(width 0)
				(type default)
			)
			(fill no)
			(layer "F.CrtYd")
		)
		(fp_poly
			(pts
				(xy -1.524 -1.778) (xy 1.524 -1.778) (xy 1.524 1.778) (xy -1.524 1.778)
			)
			(stroke
				(width 0)
				(type default)
			)
			(fill no)
			(layer "F.Fab")
		)
		(pad "1" smd rect
			(at -0.65024 0.9398)
			(size 0.4064 1.016)
			(layers "F.Cu" "F.Mask" "F.Paste")
			(net "P3V3_HDD13_LED")
		)
		(pad "2" smd rect
			(at 0 0.9398)
			(size 0.4064 1.016)
			(layers "F.Cu" "F.Mask" "F.Paste")
			(net "HDD13_LED_G")
		)
		(pad "3" smd rect
			(at 0.65024 0.9398)
			(size 0.4064 1.016)
			(layers "F.Cu" "F.Mask" "F.Paste")
			(net "P5VC")
		)
		(pad "4" smd rect
			(at 0.65024 -0.9398)
			(size 0.4064 1.016)
			(layers "F.Cu" "F.Mask" "F.Paste")
			(net "P5VC_HDD13_LED")
		)
		(pad "5" smd rect
			(at 0 -0.9398)
			(size 0.4064 1.016)
			(layers "F.Cu" "F.Mask" "F.Paste")
			(net "HDD13_LED_G")
		)
		(pad "6" smd rect
			(at -0.65024 -0.9398)
			(size 0.4064 1.016)
			(layers "F.Cu" "F.Mask" "F.Paste")
			(net "P3V3")
		)
	)
	(footprint ""
		(layer "F.Cu")
		(at 11.8618 -161.417 90)
		(property "Reference" "R357"
			(at 0 0 90)
			(layer "F.SilkS")
			(hide yes)
			(effects
				(font
					(size 1.27 1.27)
				)
			)
		)
		(property "Value" "0R2J-2-GP"
			(at 0.064008 -3.993896 90)
			(unlocked yes)
			(layer "F.Fab")
			(hide yes)
			(effects
				(font
					(size 1.016 1.016)
					(thickness 0.1524)
				)
			)
		)
		(property "Device Type" "R402H16"
			(at 0.064008 -5.517896 90)
			(unlocked yes)
			(layer "F.Fab")
			(hide yes)
			(effects
				(font
					(size 1.016 1.016)
					(thickness 0.1524)
				)
			)
		)
		(duplicate_pad_numbers_are_jumpers no)
		(fp_line
			(start 0.508 -0.9398)
			(end -0.508 -0.9398)
			(stroke
				(width 0.1524)
				(type default)
			)
			(layer "F.SilkS")
		)
		(fp_line
			(start -0.508 -0.9398)
			(end -0.508 0.9398)
			(stroke
				(width 0.1524)
				(type default)
			)
			(layer "F.SilkS")
		)
		(fp_rect
			(start -0.508 0.9398)
			(end 0.508 -0.9398)
			(stroke
				(width 0)
				(type default)
			)
			(fill no)
			(layer "F.CrtYd")
		)
		(fp_rect
			(start -0.508 0.9398)
			(end 0.508 -0.9398)
			(stroke
				(width 0)
				(type default)
			)
			(fill no)
			(layer "F.Fab")
		)
		(pad "1" smd custom
			(at 0 -0.4445 90)
			(size 0.1397 0.1397)
			(layers "F.Cu" "F.Mask" "F.Paste")
			(net "SELF_1A&2A_HB")
			(options
				(clearance outline)
				(anchor circle)
			)
			(primitives
				(gr_poly
					(pts
						(arc
							(start -0.1778 -0.2794)
							(mid -0.249642 -0.249642)
							(end -0.2794 -0.1778)
						)
						(arc
							(start -0.2794 0.1778)
							(mid -0.249642 0.249642)
							(end -0.1778 0.2794)
						)
						(arc
							(start 0.1778 0.2794)
							(mid 0.249642 0.249642)
							(end 0.2794 0.1778)
						)
						(arc
							(start 0.2794 -0.1778)
							(mid 0.249642 -0.249642)
							(end 0.1778 -0.2794)
						)
					)
					(width 0)
					(fill yes)
				)
			)
		)
		(pad "2" smd custom
			(at 0 0.4445 90)
			(size 0.1397 0.1397)
			(layers "F.Cu" "F.Mask" "F.Paste")
			(net "HB_EXP_B_INPUT")
			(options
				(clearance outline)
				(anchor circle)
			)
			(primitives
				(gr_poly
					(pts
						(arc
							(start -0.1778 -0.2794)
							(mid -0.249642 -0.249642)
							(end -0.2794 -0.1778)
						)
						(arc
							(start -0.2794 0.1778)
							(mid -0.249642 0.249642)
							(end -0.1778 0.2794)
						)
						(arc
							(start 0.1778 0.2794)
							(mid 0.249642 0.249642)
							(end 0.2794 0.1778)
						)
						(arc
							(start 0.2794 -0.1778)
							(mid 0.249642 -0.249642)
							(end 0.1778 -0.2794)
						)
					)
					(width 0)
					(fill yes)
				)
			)
		)
	)
)
